(kicad_pcb
	(version 20260206)
	(generator "pcbnew")
	(generator_version "10.0")
	(general
		(thickness 1.6)
		(legacy_teardrops no)
	)
	(paper "A4")
	(title_block
		(title "peb — Lightning_PEB_BRD.brd")
		(comment 1 "Lightning (Wiwynn / Facebook NVMe JBOF) / footprints 1153-1161 of 2563")
	)
	(layers
		(0 "F.Cu" signal "TOP")
		(4 "In1.Cu" signal "L2GND")
		(6 "In2.Cu" signal "L3")
		(8 "In3.Cu" signal "L4VCC")
		(10 "In4.Cu" signal "L5VCC")
		(12 "In5.Cu" signal "L6")
		(14 "In6.Cu" signal "L7GND")
		(2 "B.Cu" signal "BOTTOM")
		(9 "F.Adhes" user "F.Adhesive")
		(11 "B.Adhes" user "B.Adhesive")
		(13 "F.Paste" user "Package Geometry/Pastemask Top")
		(15 "B.Paste" user "Package Geometry/Pastemask Bottom")
		(5 "F.SilkS" user "Ref Des/Silkscreen Top")
		(7 "B.SilkS" user "Ref Des/Silkscreen Bottom")
		(1 "F.Mask" user "Board Geometry/Soldermask Top")
		(3 "B.Mask" user "Board Geometry/Soldermask Bottom")
		(17 "Dwgs.User" user "User.Drawings")
		(19 "Cmts.User" user "User.Comments")
		(21 "Eco1.User" user "User.Eco1")
		(23 "Eco2.User" user "User.Eco2")
		(25 "Edge.Cuts" user "Board Geometry/Outline")
		(27 "Margin" user)
		(31 "F.CrtYd" user "Package Geometry/Place Bound Top")
		(29 "B.CrtYd" user "Package Geometry/Place Bound Bottom")
		(35 "F.Fab" user "Ref Des/Assembly Top")
		(33 "B.Fab" user "Ref Des/Assembly Bottom")
	)
	(footprint ""
		(layer "F.Cu")
		(at 44.323 -142.621)
		(property "Reference" "TP232"
			(at 0 0 0)
			(layer "F.SilkS")
			(hide yes)
			(effects
				(font
					(size 1.27 1.27)
				)
			)
		)
		(property "Value" "TPAD28-2-GP"
			(at -0.0127 -1.6637 0)
			(unlocked yes)
			(layer "F.Fab")
			(hide yes)
			(effects
				(font
					(size 1.016 1.016)
					(thickness 0.1524)
				)
			)
		)
		(property "Device Type" "TPAD28"
			(at -0.0127 -3.1877 0)
			(unlocked yes)
			(layer "F.Fab")
			(hide yes)
			(effects
				(font
					(size 1.016 1.016)
					(thickness 0.1524)
				)
			)
		)
		(duplicate_pad_numbers_are_jumpers no)
		(fp_poly
			(pts
				(arc
					(start 0.3556 0)
					(mid -0.3556 0)
					(end 0.3556 0)
				)
			)
			(stroke
				(width 0)
				(type default)
			)
			(fill no)
			(layer "F.CrtYd")
		)
		(fp_poly
			(pts
				(arc
					(start 0.6096 0)
					(mid -0.6096 0)
					(end 0.6096 0)
				)
			)
			(stroke
				(width 0)
				(type default)
			)
			(fill no)
			(layer "F.Fab")
		)
		(pad "1" smd circle
			(at 0 0)
			(size 0.7112 0.7112)
			(layers "F.Cu" "F.Mask" "F.Paste")
			(net "TP_GPIOP6")
		)
	)
	(footprint ""
		(layer "F.Cu")
		(at 213.808056 -212.420454 180)
		(property "Reference" "C110"
			(at 0 0 180)
			(layer "F.SilkS")
			(hide yes)
			(effects
				(font
					(size 1.27 1.27)
				)
			)
		)
		(property "Value" "SCD22U10V2KX-1GP"
			(at 1.1811 -2.7051 180)
			(unlocked yes)
			(layer "F.Fab")
			(hide yes)
			(effects
				(font
					(size 1.016 1.016)
					(thickness 0.1524)
				)
			)
		)
		(property "Device Type" "C402H22"
			(at 1.1811 -4.2291 180)
			(unlocked yes)
			(layer "F.Fab")
			(hide yes)
			(effects
				(font
					(size 1.016 1.016)
					(thickness 0.1524)
				)
			)
		)
		(duplicate_pad_numbers_are_jumpers no)
		(fp_rect
			(start -0.4318 0.9525)
			(end 0.4318 -0.9525)
			(stroke
				(width 0)
				(type default)
			)
			(fill no)
			(layer "F.CrtYd")
		)
		(fp_rect
			(start -0.4318 0.9525)
			(end 0.4318 -0.9525)
			(stroke
				(width 0)
				(type default)
			)
			(fill no)
			(layer "F.Fab")
		)
		(pad "1" smd custom
			(at 0 -0.4445 180)
			(size 0.1524 0.1524)
			(layers "F.Cu" "F.Mask" "F.Paste")
			(net "PCIE_TX_CAP_N39")
			(options
				(clearance outline)
				(anchor circle)
			)
			(primitives
				(gr_poly
					(pts
						(arc
							(start 0.3048 -0.2032)
							(mid 0.275042 -0.275042)
							(end 0.2032 -0.3048)
						)
						(arc
							(start -0.2032 -0.3048)
							(mid -0.275042 -0.275042)
							(end -0.3048 -0.2032)
						)
						(arc
							(start -0.3048 0.2032)
							(mid -0.275042 0.275042)
							(end -0.2032 0.3048)
						)
						(arc
							(start 0.2032 0.3048)
							(mid 0.275042 0.275042)
							(end 0.3048 0.2032)
						)
					)
					(width 0)
					(fill yes)
				)
			)
		)
		(pad "2" smd custom
			(at 0 0.4445 180)
			(size 0.1524 0.1524)
			(layers "F.Cu" "F.Mask" "F.Paste")
			(net "PCIE_TX_N39")
			(options
				(clearance outline)
				(anchor circle)
			)
			(primitives
				(gr_poly
					(pts
						(arc
							(start 0.3048 -0.2032)
							(mid 0.275042 -0.275042)
							(end 0.2032 -0.3048)
						)
						(arc
							(start -0.2032 -0.3048)
							(mid -0.275042 -0.275042)
							(end -0.3048 -0.2032)
						)
						(arc
							(start -0.3048 0.2032)
							(mid -0.275042 0.275042)
							(end -0.2032 0.3048)
						)
						(arc
							(start 0.2032 0.3048)
							(mid 0.275042 0.275042)
							(end 0.3048 0.2032)
						)
					)
					(width 0)
					(fill yes)
				)
			)
		)
	)
	(footprint ""
		(layer "F.Cu")
		(at 53.721 -127.508 90)
		(property "Reference" "R451"
			(at 0 0 90)
			(layer "F.SilkS")
			(hide yes)
			(effects
				(font
					(size 1.27 1.27)
				)
			)
		)
		(property "Value" "0R2J-2-GP"
			(at 0.064008 -3.993896 90)
			(unlocked yes)
			(layer "F.Fab")
			(hide yes)
			(effects
				(font
					(size 1.016 1.016)
					(thickness 0.1524)
				)
			)
		)
		(property "Device Type" "R402H16"
			(at 0.064008 -5.517896 90)
			(unlocked yes)
			(layer "F.Fab")
			(hide yes)
			(effects
				(font
					(size 1.016 1.016)
					(thickness 0.1524)
				)
			)
		)
		(duplicate_pad_numbers_are_jumpers no)
		(fp_line
			(start 0.508 -0.9398)
			(end -0.508 -0.9398)
			(stroke
				(width 0.1524)
				(type default)
			)
			(layer "F.SilkS")
		)
		(fp_line
			(start -0.508 -0.9398)
			(end -0.508 0.9398)
			(stroke
				(width 0.1524)
				(type default)
			)
			(layer "F.SilkS")
		)
		(fp_rect
			(start -0.508 0.9398)
			(end 0.508 -0.9398)
			(stroke
				(width 0)
				(type default)
			)
			(fill no)
			(layer "F.CrtYd")
		)
		(fp_rect
			(start -0.508 0.9398)
			(end 0.508 -0.9398)
			(stroke
				(width 0)
				(type default)
			)
			(fill no)
			(layer "F.Fab")
		)
		(pad "1" smd custom
			(at 0 -0.4445 90)
			(size 0.1397 0.1397)
			(layers "F.Cu" "F.Mask" "F.Paste")
			(net "BMC_USB1_HDP")
			(options
				(clearance outline)
				(anchor circle)
			)
			(primitives
				(gr_poly
					(pts
						(arc
							(start -0.1778 -0.2794)
							(mid -0.249642 -0.249642)
							(end -0.2794 -0.1778)
						)
						(arc
							(start -0.2794 0.1778)
							(mid -0.249642 0.249642)
							(end -0.1778 0.2794)
						)
						(arc
							(start 0.1778 0.2794)
							(mid 0.249642 0.249642)
							(end 0.2794 0.1778)
						)
						(arc
							(start 0.2794 -0.1778)
							(mid 0.249642 -0.249642)
							(end 0.1778 -0.2794)
						)
					)
					(width 0)
					(fill yes)
				)
			)
		)
		(pad "2" smd custom
			(at 0 0.4445 90)
			(size 0.1397 0.1397)
			(layers "F.Cu" "F.Mask" "F.Paste")
			(net "USB_P2_DP")
			(options
				(clearance outline)
				(anchor circle)
			)
			(primitives
				(gr_poly
					(pts
						(arc
							(start -0.1778 -0.2794)
							(mid -0.249642 -0.249642)
							(end -0.2794 -0.1778)
						)
						(arc
							(start -0.2794 0.1778)
							(mid -0.249642 0.249642)
							(end -0.1778 0.2794)
						)
						(arc
							(start 0.1778 0.2794)
							(mid 0.249642 0.249642)
							(end 0.2794 0.1778)
						)
						(arc
							(start 0.2794 -0.1778)
							(mid 0.249642 -0.249642)
							(end 0.1778 -0.2794)
						)
					)
					(width 0)
					(fill yes)
				)
			)
		)
	)
	(footprint ""
		(layer "F.Cu")
		(at 62.611 -133.985)
		(property "Reference" "C8083"
			(at 0 0 0)
			(layer "F.SilkS")
			(hide yes)
			(effects
				(font
					(size 1.27 1.27)
				)
			)
		)
		(property "Value" "SCD1U25V2KX-2-GP"
			(at 1.1811 -2.7051 0)
			(unlocked yes)
			(layer "F.Fab")
			(hide yes)
			(effects
				(font
					(size 1.016 1.016)
					(thickness 0.1524)
				)
			)
		)
		(property "Device Type" "C402H22"
			(at 1.1811 -4.2291 0)
			(unlocked yes)
			(layer "F.Fab")
			(hide yes)
			(effects
				(font
					(size 1.016 1.016)
					(thickness 0.1524)
				)
			)
		)
		(duplicate_pad_numbers_are_jumpers no)
		(fp_rect
			(start -0.4318 0.9525)
			(end 0.4318 -0.9525)
			(stroke
				(width 0)
				(type default)
			)
			(fill no)
			(layer "F.CrtYd")
		)
		(fp_rect
			(start -0.4318 0.9525)
			(end 0.4318 -0.9525)
			(stroke
				(width 0)
				(type default)
			)
			(fill no)
			(layer "F.Fab")
		)
		(pad "1" smd custom
			(at 0 -0.4445)
			(size 0.1524 0.1524)
			(layers "F.Cu" "F.Mask" "F.Paste")
			(net "ADC_P0V9")
			(options
				(clearance outline)
				(anchor circle)
			)
			(primitives
				(gr_poly
					(pts
						(arc
							(start 0.3048 -0.2032)
							(mid 0.275042 -0.275042)
							(end 0.2032 -0.3048)
						)
						(arc
							(start -0.2032 -0.3048)
							(mid -0.275042 -0.275042)
							(end -0.3048 -0.2032)
						)
						(arc
							(start -0.3048 0.2032)
							(mid -0.275042 0.275042)
							(end -0.2032 0.3048)
						)
						(arc
							(start 0.2032 0.3048)
							(mid 0.275042 0.275042)
							(end 0.3048 0.2032)
						)
					)
					(width 0)
					(fill yes)
				)
			)
		)
		(pad "2" smd custom
			(at 0 0.4445)
			(size 0.1524 0.1524)
			(layers "F.Cu" "F.Mask" "F.Paste")
			(net "GND")
			(options
				(clearance outline)
				(anchor circle)
			)
			(primitives
				(gr_poly
					(pts
						(arc
							(start 0.3048 -0.2032)
							(mid 0.275042 -0.275042)
							(end 0.2032 -0.3048)
						)
						(arc
							(start -0.2032 -0.3048)
							(mid -0.275042 -0.275042)
							(end -0.3048 -0.2032)
						)
						(arc
							(start -0.3048 0.2032)
							(mid -0.275042 0.275042)
							(end -0.2032 0.3048)
						)
						(arc
							(start 0.2032 0.3048)
							(mid 0.275042 0.275042)
							(end 0.3048 0.2032)
						)
					)
					(width 0)
					(fill yes)
				)
			)
		)
	)
	(footprint ""
		(layer "F.Cu")
		(at 230.251 -10.414 90)
		(property "Reference" "R652"
			(at 0 0 90)
			(layer "F.SilkS")
			(hide yes)
			(effects
				(font
					(size 1.27 1.27)
				)
			)
		)
		(property "Value" "100KR2F-L1-GP"
			(at 0.064008 -3.993896 90)
			(unlocked yes)
			(layer "F.Fab")
			(hide yes)
			(effects
				(font
					(size 1.016 1.016)
					(thickness 0.1524)
				)
			)
		)
		(property "Device Type" "R402H16"
			(at 0.064008 -5.517896 90)
			(unlocked yes)
			(layer "F.Fab")
			(hide yes)
			(effects
				(font
					(size 1.016 1.016)
					(thickness 0.1524)
				)
			)
		)
		(duplicate_pad_numbers_are_jumpers no)
		(fp_line
			(start 0.508 -0.9398)
			(end -0.508 -0.9398)
			(stroke
				(width 0.1524)
				(type default)
			)
			(layer "F.SilkS")
		)
		(fp_line
			(start -0.508 -0.9398)
			(end -0.508 0.9398)
			(stroke
				(width 0.1524)
				(type default)
			)
			(layer "F.SilkS")
		)
		(fp_rect
			(start -0.508 0.9398)
			(end 0.508 -0.9398)
			(stroke
				(width 0)
				(type default)
			)
			(fill no)
			(layer "F.CrtYd")
		)
		(fp_rect
			(start -0.508 0.9398)
			(end 0.508 -0.9398)
			(stroke
				(width 0)
				(type default)
			)
			(fill no)
			(layer "F.Fab")
		)
		(pad "1" smd custom
			(at 0 -0.4445 90)
			(size 0.1397 0.1397)
			(layers "F.Cu" "F.Mask" "F.Paste")
			(net "EEPROM_WP_8536")
			(options
				(clearance outline)
				(anchor circle)
			)
			(primitives
				(gr_poly
					(pts
						(arc
							(start -0.1778 -0.2794)
							(mid -0.249642 -0.249642)
							(end -0.2794 -0.1778)
						)
						(arc
							(start -0.2794 0.1778)
							(mid -0.249642 0.249642)
							(end -0.1778 0.2794)
						)
						(arc
							(start 0.1778 0.2794)
							(mid 0.249642 0.249642)
							(end 0.2794 0.1778)
						)
						(arc
							(start 0.2794 -0.1778)
							(mid 0.249642 -0.249642)
							(end 0.1778 -0.2794)
						)
					)
					(width 0)
					(fill yes)
				)
			)
		)
		(pad "2" smd custom
			(at 0 0.4445 90)
			(size 0.1397 0.1397)
			(layers "F.Cu" "F.Mask" "F.Paste")
			(net "GND")
			(options
				(clearance outline)
				(anchor circle)
			)
			(primitives
				(gr_poly
					(pts
						(arc
							(start -0.1778 -0.2794)
							(mid -0.249642 -0.249642)
							(end -0.2794 -0.1778)
						)
						(arc
							(start -0.2794 0.1778)
							(mid -0.249642 0.249642)
							(end -0.1778 0.2794)
						)
						(arc
							(start 0.1778 0.2794)
							(mid 0.249642 0.249642)
							(end 0.2794 0.1778)
						)
						(arc
							(start 0.2794 -0.1778)
							(mid 0.249642 -0.249642)
							(end 0.1778 -0.2794)
						)
					)
					(width 0)
					(fill yes)
				)
			)
		)
	)
	(footprint ""
		(layer "F.Cu")
		(at 345.60002 -34.499804)
		(property "Reference" ""
			(at 0 0 0)
			(layer "F.SilkS")
			(hide yes)
			(effects
				(font
					(size 1.27 1.27)
				)
			)
		)
		(property "Value" "*"
			(at -0.1524 -7.3914 0)
			(unlocked yes)
			(layer "F.Fab")
			(hide yes)
			(effects
				(font
					(size 1.016 1.016)
					(thickness 0.1524)
				)
			)
		)
		(duplicate_pad_numbers_are_jumpers no)
		(fp_poly
			(pts
				(arc
					(start 4.3053 0)
					(mid -4.3053 0)
					(end 4.3053 0)
				)
			)
			(stroke
				(width 0)
				(type default)
			)
			(fill no)
			(layer "B.CrtYd")
		)
		(fp_poly
			(pts
				(arc
					(start 4.3053 0)
					(mid -4.3053 0)
					(end 4.3053 0)
				)
			)
			(stroke
				(width 0)
				(type default)
			)
			(fill no)
			(layer "F.CrtYd")
		)
		(fp_poly
			(pts
				(arc
					(start 4.3053 0)
					(mid -4.3053 0)
					(end 4.3053 0)
				)
			)
			(stroke
				(width 0)
				(type default)
			)
			(fill no)
			(layer "B.Fab")
		)
		(fp_poly
			(pts
				(arc
					(start 4.3053 0)
					(mid -4.3053 0)
					(end 4.3053 0)
				)
			)
			(stroke
				(width 0)
				(type default)
			)
			(fill no)
			(layer "F.Fab")
		)
		(pad "1" thru_hole circle
			(at 0 0)
			(size 8.001 8.001)
			(drill 3.81)
			(layers "*.Cu" "*.Mask")
			(remove_unused_layers no)
			(net "Net_116")
			(clearance -1.5875)
			(thermal_gap 0.3048)
			(padstack
				(mode front_inner_back)
				(layer "Inner"
					(shape circle)
					(size 4.2164 4.2164)
					(clearance 0.3048)
				)
				(layer "B.Cu"
					(shape circle)
					(size 8.001 8.001)
					(clearance -1.5875)
				)
			)
		)
	)
	(footprint ""
		(layer "F.Cu")
		(at 308.102 -57.0992)
		(property "Reference" "C439"
			(at 0 0 0)
			(layer "F.SilkS")
			(hide yes)
			(effects
				(font
					(size 1.27 1.27)
				)
			)
		)
		(property "Value" "SC10U16V5KX-1-GP"
			(at -0.0762 -6.1214 0)
			(unlocked yes)
			(layer "F.Fab")
			(hide yes)
			(effects
				(font
					(size 1.016 1.016)
					(thickness 0.1524)
				)
			)
		)
		(property "Device Type" "C805H54"
			(at -0.0762 -8.1534 0)
			(unlocked yes)
			(layer "F.Fab")
			(hide yes)
			(effects
				(font
					(size 1.016 1.016)
					(thickness 0.1524)
				)
			)
		)
		(duplicate_pad_numbers_are_jumpers no)
		(fp_line
			(start 0.635 0)
			(end -0.635 0)
			(stroke
				(width 0.508)
				(type default)
			)
			(layer "F.SilkS")
		)
		(fp_rect
			(start -0.9652 1.778)
			(end 0.9652 -1.778)
			(stroke
				(width 0)
				(type default)
			)
			(fill no)
			(layer "F.CrtYd")
		)
		(fp_poly
			(pts
				(xy -0.9652 -1.778) (xy 0.9652 -1.778) (xy 0.9652 1.778) (xy -0.9652 1.778)
			)
			(stroke
				(width 0)
				(type default)
			)
			(fill no)
			(layer "F.Fab")
		)
		(pad "1" smd rect
			(at 0 -0.9652)
			(size 1.397 1.143)
			(layers "F.Cu" "F.Mask" "F.Paste")
			(net "DUT_VDD")
		)
		(pad "2" smd rect
			(at 0 0.9652)
			(size 1.397 1.143)
			(layers "F.Cu" "F.Mask" "F.Paste")
			(net "GND")
		)
	)
	(footprint ""
		(layer "F.Cu")
		(at 181.61 -20.701 -90)
		(property "Reference" "C411"
			(at 0 0 270)
			(layer "F.SilkS")
			(hide yes)
			(effects
				(font
					(size 1.27 1.27)
				)
			)
		)
		(property "Value" "SCD22U10V2KX-1GP"
			(at 1.1811 -2.7051 270)
			(unlocked yes)
			(layer "F.Fab")
			(hide yes)
			(effects
				(font
					(size 1.016 1.016)
					(thickness 0.1524)
				)
			)
		)
		(property "Device Type" "C402H22"
			(at 1.1811 -4.2291 270)
			(unlocked yes)
			(layer "F.Fab")
			(hide yes)
			(effects
				(font
					(size 1.016 1.016)
					(thickness 0.1524)
				)
			)
		)
		(duplicate_pad_numbers_are_jumpers no)
		(fp_rect
			(start -0.4318 0.9525)
			(end 0.4318 -0.9525)
			(stroke
				(width 0)
				(type default)
			)
			(fill no)
			(layer "F.CrtYd")
		)
		(fp_rect
			(start -0.4318 0.9525)
			(end 0.4318 -0.9525)
			(stroke
				(width 0)
				(type default)
			)
			(fill no)
			(layer "F.Fab")
		)
		(pad "1" smd custom
			(at 0 -0.4445 270)
			(size 0.1524 0.1524)
			(layers "F.Cu" "F.Mask" "F.Paste")
			(net "PCIE_TX_CAP_P95")
			(options
				(clearance outline)
				(anchor circle)
			)
			(primitives
				(gr_poly
					(pts
						(arc
							(start 0.3048 -0.2032)
							(mid 0.275042 -0.275042)
							(end 0.2032 -0.3048)
						)
						(arc
							(start -0.2032 -0.3048)
							(mid -0.275042 -0.275042)
							(end -0.3048 -0.2032)
						)
						(arc
							(start -0.3048 0.2032)
							(mid -0.275042 0.275042)
							(end -0.2032 0.3048)
						)
						(arc
							(start 0.2032 0.3048)
							(mid 0.275042 0.275042)
							(end 0.3048 0.2032)
						)
					)
					(width 0)
					(fill yes)
				)
			)
		)
		(pad "2" smd custom
			(at 0 0.4445 270)
			(size 0.1524 0.1524)
			(layers "F.Cu" "F.Mask" "F.Paste")
			(net "PCIE_TX_P95")
			(options
				(clearance outline)
				(anchor circle)
			)
			(primitives
				(gr_poly
					(pts
						(arc
							(start 0.3048 -0.2032)
							(mid 0.275042 -0.275042)
							(end 0.2032 -0.3048)
						)
						(arc
							(start -0.2032 -0.3048)
							(mid -0.275042 -0.275042)
							(end -0.3048 -0.2032)
						)
						(arc
							(start -0.3048 0.2032)
							(mid -0.275042 0.275042)
							(end -0.2032 0.3048)
						)
						(arc
							(start 0.2032 0.3048)
							(mid 0.275042 0.275042)
							(end 0.3048 0.2032)
						)
					)
					(width 0)
					(fill yes)
				)
			)
		)
	)
	(footprint ""
		(layer "F.Cu")
		(at 70.1802 -158.8516)
		(property "Reference" "PC95"
			(at 0 0 0)
			(layer "F.SilkS")
			(hide yes)
			(effects
				(font
					(size 1.27 1.27)
				)
			)
		)
		(property "Value" "SC22U6D3V5MX-5-GP"
			(at -0.0762 -6.1214 0)
			(unlocked yes)
			(layer "F.Fab")
			(hide yes)
			(effects
				(font
					(size 1.016 1.016)
					(thickness 0.1524)
				)
			)
		)
		(property "Device Type" "C805H56"
			(at -0.0762 -8.1534 0)
			(unlocked yes)
			(layer "F.Fab")
			(hide yes)
			(effects
				(font
					(size 1.016 1.016)
					(thickness 0.1524)
				)
			)
		)
		(duplicate_pad_numbers_are_jumpers no)
		(fp_line
			(start 0.635 0)
			(end -0.635 0)
			(stroke
				(width 0.508)
				(type default)
			)
			(layer "F.SilkS")
		)
		(fp_rect
			(start -0.9652 1.778)
			(end 0.9652 -1.778)
			(stroke
				(width 0)
				(type default)
			)
			(fill no)
			(layer "F.CrtYd")
		)
		(fp_poly
			(pts
				(xy -0.9652 -1.778) (xy 0.9652 -1.778) (xy 0.9652 1.778) (xy -0.9652 1.778)
			)
			(stroke
				(width 0)
				(type default)
			)
			(fill no)
			(layer "F.Fab")
		)
		(pad "1" smd rect
			(at 0 -0.9652)
			(size 1.397 1.143)
			(layers "F.Cu" "F.Mask" "F.Paste")
			(net "VR_P1V538_STBY_IN")
		)
		(pad "2" smd rect
			(at 0 0.9652)
			(size 1.397 1.143)
			(layers "F.Cu" "F.Mask" "F.Paste")
			(net "GND")
		)
	)
)
